# T6G (Grand Teton) — schematic netlist excerpt (pin names and nets, part order shuffled) for the footprints in the layout excerpt that follows; sources: Cadence DE-HDL packaged netlist, KiCad conversion of 04192023_DAF0TMB3IC0_F0TG_MB_C_brd_V02_OCP.brd

C6593  Q_CAP_DIFFBUS  DIFF BUS_0.22UF 6.3V 20% X6S  pkg C0201  page 297 : \1\ = P5E_CPU0_P2_TX_BUF_C_DP<14> ; \2\ = P5E_CPU0_P2_TX_BUF_DP<14>
PC586_2  Q_CAP  0.1UF 25V 10% X7R  pkg 0402  page 198 : A = SW_P12V_AUX_PVDDCR_SOC_P0_FLT ; B = GND
R670  Q_RES  49.9 1% CHIP  pkg 0201LF  page 331 : A = SMB_RT_CPU1_P1_ROM_MUX_1D_SCL ; B = SMB_RT_CPU1_P1_ROM_MUX_1D_R_SCL

(kicad_pcb
	(version 20260206)
	(generator "pcbnew")
	(generator_version "10.0")
	(general
		(thickness 1.6)
		(legacy_teardrops no)
	)
	(paper "A4")
	(title_block
		(title "04192023_DAF0TMB3IC0_F0TG_MB_C_brd_V02_OCP.brd")
		(comment 1 "Grand Teton / footprints 2470-2472 of 8354")
	)
	(layers
		(0 "F.Cu" signal "TOP")
		(4 "In1.Cu" signal "GND")
		(6 "In2.Cu" signal "IN1")
		(8 "In3.Cu" signal "GND1")
		(10 "In4.Cu" signal "IN2")
		(12 "In5.Cu" signal "GND2")
		(14 "In6.Cu" signal "IN3")
		(16 "In7.Cu" signal "GND3")
		(18 "In8.Cu" signal "VCC")
		(20 "In9.Cu" signal "VCC1")
		(22 "In10.Cu" signal "GND4")
		(24 "In11.Cu" signal "IN4")
		(26 "In12.Cu" signal "GND5")
		(28 "In13.Cu" signal "IN5")
		(30 "In14.Cu" signal "GND6")
		(32 "In15.Cu" signal "IN6")
		(34 "In16.Cu" signal "GND7")
		(2 "B.Cu" signal "BOTTOM")
		(9 "F.Adhes" user "F.Adhesive")
		(11 "B.Adhes" user "B.Adhesive")
		(13 "F.Paste" user "Package Geometry/Pastemask Top")
		(15 "B.Paste" user "Package Geometry/Pastemask Bottom")
		(5 "F.SilkS" user "Ref Des/Silkscreen Top")
		(7 "B.SilkS" user "Ref Des/Silkscreen Bottom")
		(1 "F.Mask" user "Board Geometry/Soldermask Top")
		(3 "B.Mask" user "Board Geometry/Soldermask Bottom")
		(17 "Dwgs.User" user "User.Drawings")
		(19 "Cmts.User" user "User.Comments")
		(21 "Eco1.User" user "User.Eco1")
		(23 "Eco2.User" user "User.Eco2")
		(25 "Edge.Cuts" user "Board Geometry/Outline")
		(27 "Margin" user)
		(31 "F.CrtYd" user "Package Geometry/Place Bound Top")
		(29 "B.CrtYd" user "Package Geometry/Place Bound Bottom")
		(35 "F.Fab" user "Ref Des/Assembly Top")
		(33 "B.Fab" user "Ref Des/Assembly Bottom")
	)
	(footprint ""
		(layer "F.Cu")
		(at 105.92816 -395.55674 180)
		(property "Reference" "R670"
			(at 0 0 180)
			(layer "F.SilkS")
			(hide yes)
			(effects
				(font
					(size 1.27 1.27)
				)
			)
		)
		(property "Value" ""
			(at 0 0 180)
			(layer "F.Fab")
			(effects
				(font
					(size 1.27 1.27)
				)
			)
		)
		(duplicate_pad_numbers_are_jumpers no)
		(fp_line
			(start 0.32512 0.175006)
			(end -0.32512 0.175006)
			(stroke
				(width 0.1)
				(type default)
			)
			(layer "F.Fab")
		)
		(fp_line
			(start 0.32512 -0.175006)
			(end 0.32512 0.175006)
			(stroke
				(width 0.1)
				(type default)
			)
			(layer "F.Fab")
		)
		(fp_line
			(start -0.32512 0.175006)
			(end -0.32512 -0.175006)
			(stroke
				(width 0.1)
				(type default)
			)
			(layer "F.Fab")
		)
		(fp_line
			(start -0.32512 -0.175006)
			(end 0.32512 -0.175006)
			(stroke
				(width 0.1)
				(type default)
			)
			(layer "F.Fab")
		)
		(pad "1" smd rect
			(at -0.2667 0 180)
			(size 0.3048 0.381)
			(layers "F.Cu" "F.Mask" "F.Paste")
			(net "SMB_RT_CPU1_P1_ROM_MUX_1D_SCL")
		)
		(pad "2" smd rect
			(at 0.2667 0)
			(size 0.3048 0.381)
			(layers "F.Cu" "F.Mask" "F.Paste")
			(net "SMB_RT_CPU1_P1_ROM_MUX_1D_R_SCL")
		)
	)
	(footprint ""
		(layer "F.Cu")
		(at 401.471638 -168.510966 90)
		(property "Reference" "PC586_2"
			(at 0 0 90)
			(layer "F.SilkS")
			(hide yes)
			(effects
				(font
					(size 1.27 1.27)
				)
			)
		)
		(property "Value" ""
			(at 0 0 90)
			(layer "F.Fab")
			(effects
				(font
					(size 1.27 1.27)
				)
			)
		)
		(duplicate_pad_numbers_are_jumpers no)
		(fp_line
			(start 0.7874 -0.4064)
			(end 0.7874 0.4064)
			(stroke
				(width 0.1524)
				(type default)
			)
			(layer "F.SilkS")
		)
		(fp_line
			(start -0.7874 -0.4064)
			(end 0.7874 -0.4064)
			(stroke
				(width 0.1524)
				(type default)
			)
			(layer "F.SilkS")
		)
		(fp_line
			(start 0.7874 0.4064)
			(end -0.7874 0.4064)
			(stroke
				(width 0.1524)
				(type default)
			)
			(layer "F.SilkS")
		)
		(fp_line
			(start -0.7874 0.4064)
			(end -0.7874 -0.4064)
			(stroke
				(width 0.1524)
				(type default)
			)
			(layer "F.SilkS")
		)
		(fp_line
			(start -0.12065 -0.305054)
			(end -0.12065 -0.2794)
			(stroke
				(width 0.1)
				(type default)
			)
			(layer "F.Fab")
		)
		(fp_line
			(start -0.67945 -0.305054)
			(end -0.12065 -0.305054)
			(stroke
				(width 0.1)
				(type default)
			)
			(layer "F.Fab")
		)
		(fp_line
			(start 0.67945 -0.3048)
			(end 0.67945 0.3048)
			(stroke
				(width 0.1)
				(type default)
			)
			(layer "F.Fab")
		)
		(fp_line
			(start 0.12065 -0.3048)
			(end 0.67945 -0.3048)
			(stroke
				(width 0.1)
				(type default)
			)
			(layer "F.Fab")
		)
		(fp_line
			(start 0.12065 -0.2794)
			(end 0.12065 -0.3048)
			(stroke
				(width 0.1)
				(type default)
			)
			(layer "F.Fab")
		)
		(fp_line
			(start -0.12065 -0.2794)
			(end 0.12065 -0.2794)
			(stroke
				(width 0.1)
				(type default)
			)
			(layer "F.Fab")
		)
		(fp_line
			(start 0.120396 0.2794)
			(end -0.12065 0.2794)
			(stroke
				(width 0.1)
				(type default)
			)
			(layer "F.Fab")
		)
		(fp_line
			(start -0.12065 0.2794)
			(end -0.12065 0.3048)
			(stroke
				(width 0.1)
				(type default)
			)
			(layer "F.Fab")
		)
		(fp_line
			(start 0.67945 0.3048)
			(end 0.120396 0.3048)
			(stroke
				(width 0.1)
				(type default)
			)
			(layer "F.Fab")
		)
		(fp_line
			(start 0.120396 0.3048)
			(end 0.120396 0.2794)
			(stroke
				(width 0.1)
				(type default)
			)
			(layer "F.Fab")
		)
		(fp_line
			(start -0.12065 0.3048)
			(end -0.67945 0.3048)
			(stroke
				(width 0.1)
				(type default)
			)
			(layer "F.Fab")
		)
		(fp_line
			(start -0.67945 0.3048)
			(end -0.67945 -0.305054)
			(stroke
				(width 0.1)
				(type default)
			)
			(layer "F.Fab")
		)
		(pad "1" smd circle
			(at -0.40005 0 90)
			(size 0 0)
			(layers "F.Cu" "F.Mask" "F.Paste")
			(net "SW_P12V_AUX_PVDDCR_SOC_P0_FLT")
		)
		(pad "2" smd circle
			(at 0.40005 0 90)
			(size 0 0)
			(layers "F.Cu" "F.Mask" "F.Paste")
			(net "GND")
		)
	)
	(footprint ""
		(layer "F.Cu")
		(at 414.668462 -416.899344 -90)
		(property "Reference" "C6593"
			(at 0 0 270)
			(layer "F.SilkS")
			(hide yes)
			(effects
				(font
					(size 1.27 1.27)
				)
			)
		)
		(property "Value" ""
			(at 0 0 270)
			(layer "F.Fab")
			(effects
				(font
					(size 1.27 1.27)
				)
			)
		)
		(duplicate_pad_numbers_are_jumpers no)
		(fp_line
			(start -0.299974 0.150114)
			(end -0.299974 -0.150114)
			(stroke
				(width 0.1)
				(type default)
			)
			(layer "F.Fab")
		)
		(fp_line
			(start 0.299974 0.150114)
			(end -0.299974 0.150114)
			(stroke
				(width 0.1)
				(type default)
			)
			(layer "F.Fab")
		)
		(fp_line
			(start -0.299974 -0.150114)
			(end 0.299974 -0.150114)
			(stroke
				(width 0.1)
				(type default)
			)
			(layer "F.Fab")
		)
		(fp_line
			(start 0.299974 -0.150114)
			(end 0.299974 0.150114)
			(stroke
				(width 0.1)
				(type default)
			)
			(layer "F.Fab")
		)
		(pad "1" smd rect
			(at -0.2667 0 270)
			(size 0.3048 0.381)
			(layers "F.Cu" "F.Mask" "F.Paste")
			(net "P5E_CPU0_P2_TX_BUF_C_DP<14>")
		)
		(pad "2" smd rect
			(at 0.2667 0 270)
			(size 0.3048 0.381)
			(layers "F.Cu" "F.Mask" "F.Paste")
			(net "P5E_CPU0_P2_TX_BUF_DP<14>")
		)
	)
)
